# BASEBOARD_FAB2 (Tioga Pass) — schematic netlist excerpt (pin names and nets, part order shuffled) for the footprints in the layout excerpt that follows; sources: Cadence DE-HDL packaged netlist, KiCad conversion of Wiwynn_Tioga_Pass_MB.brd

R3R9  RES  20.0 1% CHIP  pkg 0402  page 99 : A = SMB_DDR_DEF_VPP_SDA_R ; B = SMB_DDR_DEF_VPP_SDA
R1L39  RES  100.0 1% CHIP  pkg 0402  page 112 : A = P1V05_PCH_STBY ; B = XDP_PRDY_N
R2T30  RES  33.2 1% CHIP  pkg 0402  page 93 : A = FM_CPU_ERR0_LVT3_K_N ; B = FM_CPU_ERR0_LVT3_N

(kicad_pcb
	(version 20260206)
	(generator "pcbnew")
	(generator_version "10.0")
	(general
		(thickness 1.6)
		(legacy_teardrops no)
	)
	(paper "A4")
	(title_block
		(title "Wiwynn_Tioga_Pass_MB.brd")
		(comment 1 "Tioga Pass / footprints 3115-3117 of 4770")
	)
	(layers
		(0 "F.Cu" signal "TOP")
		(4 "In1.Cu" signal "L2GND")
		(6 "In2.Cu" signal "L3")
		(8 "In3.Cu" signal "L4GND")
		(10 "In4.Cu" signal "L5")
		(12 "In5.Cu" signal "L6GND")
		(14 "In6.Cu" signal "L7VCC")
		(16 "In7.Cu" signal "L8VCC")
		(18 "In8.Cu" signal "L9GND")
		(20 "In9.Cu" signal "L10")
		(22 "In10.Cu" signal "L11GND")
		(24 "In11.Cu" signal "L12")
		(26 "In12.Cu" signal "L13GND")
		(2 "B.Cu" signal "BOTTOM")
		(9 "F.Adhes" user "F.Adhesive")
		(11 "B.Adhes" user "B.Adhesive")
		(13 "F.Paste" user "Package Geometry/Pastemask Top")
		(15 "B.Paste" user "Package Geometry/Pastemask Bottom")
		(5 "F.SilkS" user "Ref Des/Silkscreen Top")
		(7 "B.SilkS" user "Ref Des/Silkscreen Bottom")
		(1 "F.Mask" user "Board Geometry/Soldermask Top")
		(3 "B.Mask" user "Board Geometry/Soldermask Bottom")
		(17 "Dwgs.User" user "User.Drawings")
		(19 "Cmts.User" user "User.Comments")
		(21 "Eco1.User" user "User.Eco1")
		(23 "Eco2.User" user "User.Eco2")
		(25 "Edge.Cuts" user "Board Geometry/Outline")
		(27 "Margin" user)
		(31 "F.CrtYd" user "Package Geometry/Place Bound Top")
		(29 "B.CrtYd" user "Package Geometry/Place Bound Bottom")
		(35 "F.Fab" user "Ref Des/Assembly Top")
		(33 "B.Fab" user "Ref Des/Assembly Bottom")
	)
	(footprint ""
		(layer "B.Cu")
		(at 361.444794 -42.305986 -90)
		(property "Reference" "R2T30"
			(at 0 0 90)
			(layer "B.SilkS")
			(hide yes)
			(effects
				(font
					(size 1.27 1.27)
				)
				(justify mirror)
			)
		)
		(property "Value" ""
			(at 0 0 90)
			(layer "B.Fab")
			(effects
				(font
					(size 1.27 1.27)
				)
				(justify mirror)
			)
		)
		(duplicate_pad_numbers_are_jumpers no)
		(fp_poly
			(pts
				(xy 0.2794 -0.1016) (xy -0.2794 -0.1016) (xy -0.2794 0.9906) (xy 0.2794 0.9906)
			)
			(stroke
				(width 0)
				(type default)
			)
			(fill no)
			(layer "B.CrtYd")
		)
		(fp_line
			(start -0.2794 0.9906)
			(end -0.2794 -0.1016)
			(stroke
				(width 0.1)
				(type default)
			)
			(layer "B.Fab")
		)
		(fp_line
			(start 0.2794 0.9906)
			(end -0.2794 0.9906)
			(stroke
				(width 0.1)
				(type default)
			)
			(layer "B.Fab")
		)
		(fp_line
			(start -0.2794 -0.1016)
			(end 0.2794 -0.1016)
			(stroke
				(width 0.1)
				(type default)
			)
			(layer "B.Fab")
		)
		(fp_line
			(start 0.2794 -0.1016)
			(end 0.2794 0.9906)
			(stroke
				(width 0.1)
				(type default)
			)
			(layer "B.Fab")
		)
		(pad "1" smd rect
			(at 0 0 90)
			(size 0.508 0.508)
			(layers "B.Cu" "B.Mask" "B.Paste")
			(net "FM_CPU_ERR0_LVT3_K_N")
		)
		(pad "2" smd rect
			(at 0 0.889 90)
			(size 0.508 0.508)
			(layers "B.Cu" "B.Mask" "B.Paste")
			(net "FM_CPU_ERR0_LVT3_N")
		)
		(zone
			(layer "B.Cu")
			(hatch none 0.5)
			(connect_pads
				(clearance 0)
			)
			(min_thickness 0.25)
			(keepout
				(tracks not_allowed)
				(vias allowed)
				(pads allowed)
				(copperpour not_allowed)
				(footprints allowed)
			)
			(placement
				(enabled no)
				(sheetname "")
			)
			(fill
				(thermal_gap 0.5)
				(thermal_bridge_width 0.5)
				(island_removal_mode 0)
			)
			(polygon
				(pts
					(xy 360.809794 -42.051986) (xy 360.809794 -42.559986) (xy 361.190794 -42.559986) (xy 361.190794 -42.051986)
				)
			)
		)
		(zone
			(layer "B.Cu")
			(hatch none 0.5)
			(connect_pads
				(clearance 0)
			)
			(min_thickness 0.25)
			(keepout
				(tracks allowed)
				(vias not_allowed)
				(pads allowed)
				(copperpour not_allowed)
				(footprints allowed)
			)
			(placement
				(enabled no)
				(sheetname "")
			)
			(fill
				(thermal_gap 0.5)
				(thermal_bridge_width 0.5)
				(island_removal_mode 0)
			)
			(polygon
				(pts
					(xy 361.190794 -42.051986) (xy 361.190794 -42.559986) (xy 360.809794 -42.559986) (xy 360.809794 -42.051986)
				)
			)
		)
	)
	(footprint ""
		(layer "B.Cu")
		(at 317.1952 -121.2342 -90)
		(property "Reference" "R3R9"
			(at 0 0 90)
			(layer "B.SilkS")
			(hide yes)
			(effects
				(font
					(size 1.27 1.27)
				)
				(justify mirror)
			)
		)
		(property "Value" ""
			(at 0 0 90)
			(layer "B.Fab")
			(effects
				(font
					(size 1.27 1.27)
				)
				(justify mirror)
			)
		)
		(duplicate_pad_numbers_are_jumpers no)
		(fp_poly
			(pts
				(xy 0.2794 -0.1016) (xy -0.2794 -0.1016) (xy -0.2794 0.9906) (xy 0.2794 0.9906)
			)
			(stroke
				(width 0)
				(type default)
			)
			(fill no)
			(layer "B.CrtYd")
		)
		(fp_line
			(start -0.2794 0.9906)
			(end -0.2794 -0.1016)
			(stroke
				(width 0.1)
				(type default)
			)
			(layer "B.Fab")
		)
		(fp_line
			(start 0.2794 0.9906)
			(end -0.2794 0.9906)
			(stroke
				(width 0.1)
				(type default)
			)
			(layer "B.Fab")
		)
		(fp_line
			(start -0.2794 -0.1016)
			(end 0.2794 -0.1016)
			(stroke
				(width 0.1)
				(type default)
			)
			(layer "B.Fab")
		)
		(fp_line
			(start 0.2794 -0.1016)
			(end 0.2794 0.9906)
			(stroke
				(width 0.1)
				(type default)
			)
			(layer "B.Fab")
		)
		(pad "1" smd rect
			(at 0 0 90)
			(size 0.508 0.508)
			(layers "B.Cu" "B.Mask" "B.Paste")
			(net "SMB_DDR_DEF_VPP_SDA_R")
		)
		(pad "2" smd rect
			(at 0 0.889 90)
			(size 0.508 0.508)
			(layers "B.Cu" "B.Mask" "B.Paste")
			(net "SMB_DDR_DEF_VPP_SDA")
		)
		(zone
			(layer "B.Cu")
			(hatch none 0.5)
			(connect_pads
				(clearance 0)
			)
			(min_thickness 0.25)
			(keepout
				(tracks not_allowed)
				(vias allowed)
				(pads allowed)
				(copperpour not_allowed)
				(footprints allowed)
			)
			(placement
				(enabled no)
				(sheetname "")
			)
			(fill
				(thermal_gap 0.5)
				(thermal_bridge_width 0.5)
				(island_removal_mode 0)
			)
			(polygon
				(pts
					(xy 316.5602 -120.9802) (xy 316.5602 -121.4882) (xy 316.9412 -121.4882) (xy 316.9412 -120.9802)
				)
			)
		)
		(zone
			(layer "B.Cu")
			(hatch none 0.5)
			(connect_pads
				(clearance 0)
			)
			(min_thickness 0.25)
			(keepout
				(tracks allowed)
				(vias not_allowed)
				(pads allowed)
				(copperpour not_allowed)
				(footprints allowed)
			)
			(placement
				(enabled no)
				(sheetname "")
			)
			(fill
				(thermal_gap 0.5)
				(thermal_bridge_width 0.5)
				(island_removal_mode 0)
			)
			(polygon
				(pts
					(xy 316.9412 -120.9802) (xy 316.9412 -121.4882) (xy 316.5602 -121.4882) (xy 316.5602 -120.9802)
				)
			)
		)
	)
	(footprint ""
		(layer "B.Cu")
		(at 462.801208 -137.414254 90)
		(property "Reference" "R1L39"
			(at 0 0 90)
			(layer "B.SilkS")
			(hide yes)
			(effects
				(font
					(size 1.27 1.27)
				)
				(justify mirror)
			)
		)
		(property "Value" ""
			(at 0 0 90)
			(layer "B.Fab")
			(effects
				(font
					(size 1.27 1.27)
				)
				(justify mirror)
			)
		)
		(duplicate_pad_numbers_are_jumpers no)
		(fp_poly
			(pts
				(xy 0.2794 -0.1016) (xy -0.2794 -0.1016) (xy -0.2794 0.9906) (xy 0.2794 0.9906)
			)
			(stroke
				(width 0)
				(type default)
			)
			(fill no)
			(layer "B.CrtYd")
		)
		(fp_line
			(start 0.2794 -0.1016)
			(end 0.2794 0.9906)
			(stroke
				(width 0.1)
				(type default)
			)
			(layer "B.Fab")
		)
		(fp_line
			(start -0.2794 -0.1016)
			(end 0.2794 -0.1016)
			(stroke
				(width 0.1)
				(type default)
			)
			(layer "B.Fab")
		)
		(fp_line
			(start 0.2794 0.9906)
			(end -0.2794 0.9906)
			(stroke
				(width 0.1)
				(type default)
			)
			(layer "B.Fab")
		)
		(fp_line
			(start -0.2794 0.9906)
			(end -0.2794 -0.1016)
			(stroke
				(width 0.1)
				(type default)
			)
			(layer "B.Fab")
		)
		(pad "1" smd rect
			(at 0 0 270)
			(size 0.508 0.508)
			(layers "B.Cu" "B.Mask" "B.Paste")
			(net "P1V05_PCH_STBY")
		)
		(pad "2" smd rect
			(at 0 0.889 270)
			(size 0.508 0.508)
			(layers "B.Cu" "B.Mask" "B.Paste")
			(net "XDP_PRDY_N")
		)
		(zone
			(layer "B.Cu")
			(hatch none 0.5)
			(connect_pads
				(clearance 0)
			)
			(min_thickness 0.25)
			(keepout
				(tracks allowed)
				(vias not_allowed)
				(pads allowed)
				(copperpour not_allowed)
				(footprints allowed)
			)
			(placement
				(enabled no)
				(sheetname "")
			)
			(fill
				(thermal_gap 0.5)
				(thermal_bridge_width 0.5)
				(island_removal_mode 0)
			)
			(polygon
				(pts
					(xy 463.055208 -137.668254) (xy 463.055208 -137.160254) (xy 463.436208 -137.160254) (xy 463.436208 -137.668254)
				)
			)
		)
		(zone
			(layer "B.Cu")
			(hatch none 0.5)
			(connect_pads
				(clearance 0)
			)
			(min_thickness 0.25)
			(keepout
				(tracks not_allowed)
				(vias allowed)
				(pads allowed)
				(copperpour not_allowed)
				(footprints allowed)
			)
			(placement
				(enabled no)
				(sheetname "")
			)
			(fill
				(thermal_gap 0.5)
				(thermal_bridge_width 0.5)
				(island_removal_mode 0)
			)
			(polygon
				(pts
					(xy 463.436208 -137.668254) (xy 463.436208 -137.160254) (xy 463.055208 -137.160254) (xy 463.055208 -137.668254)
				)
			)
		)
	)
)
